G04 ================== begin FILE IDENTIFICATION RECORD ==================*
G04 Layout Name:  12433-1M.brd*
G04 Film Name:    WSILK_T*
G04 File Format:  Gerber RS274X*
G04 File Origin:  Cadence Allegro 16.2-S037*
G04 Origin Date:  Fri Dec 07 18:55:09 2012*
G04 *
G04 Layer:  DRAWING FORMAT/LAYER_WSILK_T*
G04 Layer:  DRAWING FORMAT/LAYER_PCB_STORY*
G04 Layer:  BOARD GEOMETRY/WSILK_T*
G04 Layer:  BOARD GEOMETRY/PANEL_OUTLINE*
G04 *
G04 Offset:    (0.00 0.00)*
G04 Mirror:    No*
G04 Mode:      Positive*
G04 Rotation:  0*
G04 FullContactRelief:  No*
G04 UndefLineWidth:     6.00*
G04 ================== end FILE IDENTIFICATION RECORD ====================*
%FSLAX35Y35*MOIN*%
%IR0*IPPOS*OFA0.00000B0.00000*MIA0B0*SFA1.00000B1.00000*%
%ADD10C,.02*%
%ADD11C,.025*%
%ADD12C,.005*%
%ADD13C,.006*%
G75*
%LPD*%
G75*
G54D10*
G01X-448201Y-82763D02*
Y-162763D01*
G01Y-118263D02*
X752899D01*
G01X-448201Y-162763D02*
X752899D01*
G01X-452201Y-66763D02*
G02I-12000J0D01*
G01X-457351D02*
G02I-6850J0D01*
G01X-464201Y-82763D02*
Y-50763D01*
G01X-448201Y-66763D02*
X-480201D01*
G01X-448201Y-82763D02*
X752899D01*
G01X-34601D02*
Y-162763D01*
G01X102899Y-82763D02*
Y-162763D01*
G01X217899Y-82763D02*
Y-162763D01*
G01X385399Y-82763D02*
Y-162763D01*
G01X555399Y-82763D02*
Y-162763D01*
G01X752899Y-82763D02*
Y-162763D01*
G01X780899Y-66763D02*
G02I-12000J0D01*
G01X775749D02*
G02I-6850J0D01*
G01X768899Y-82763D02*
Y-50763D01*
G01X784899Y-66763D02*
X752899D01*
G54D11*
G01X109500Y1633500D02*
X91500D01*
Y1640700D01*
X92400Y1643100D01*
X94500Y1644900D01*
X96900Y1645500D01*
X99300Y1644900D01*
X101100Y1643400D01*
X102001Y1640700D01*
Y1633500D01*
G01X91500Y1649100D02*
X109500Y1653300D01*
X91500Y1658100D01*
X109500Y1662900D01*
X91500Y1667100D01*
G01X109500Y1670700D02*
X91500D01*
Y1678200D01*
X92400Y1680600D01*
X93600Y1682100D01*
X96000Y1682700D01*
X98400Y1682100D01*
X99900Y1680300D01*
X100800Y1678200D01*
Y1670700D01*
G01Y1678200D02*
X109500Y1682700D01*
G01X161500Y1641800D02*
Y1647800D01*
X166900D01*
X168700Y1646000D01*
X169900Y1643900D01*
X170500Y1640900D01*
X169900Y1637900D01*
X168700Y1635800D01*
X166900Y1634000D01*
X164800Y1632800D01*
X162400Y1632200D01*
X160300D01*
X158500Y1632800D01*
X156400Y1634000D01*
X154600Y1635800D01*
X153400Y1637600D01*
X152500Y1640000D01*
Y1642100D01*
X153100Y1644500D01*
X154300Y1646300D01*
G01X170500Y1651700D02*
X152500D01*
X170500Y1665500D01*
X152500D01*
G01X170500Y1670600D02*
X152500D01*
Y1676600D01*
X153400Y1679000D01*
X154600Y1680800D01*
X156400Y1682300D01*
X158500Y1683500D01*
X161500Y1683800D01*
X164500Y1683500D01*
X166600Y1682300D01*
X168400Y1680800D01*
X169600Y1679000D01*
X170500Y1676600D01*
Y1670600D01*
G54D12*
G01X55200Y301233D02*
X58067D01*
X58667Y301500D01*
X59067Y302033D01*
X59200Y302700D01*
X59067Y303367D01*
X58667Y303900D01*
X58067Y304167D01*
X55200D01*
G01X59200Y305867D02*
X55200D01*
Y307467D01*
X55400Y308000D01*
X55867Y308400D01*
X56400Y308533D01*
X56933Y308400D01*
X57333Y308067D01*
X57533Y307467D01*
Y305867D01*
G01X59200Y310367D02*
X55200D01*
Y311967D01*
X55400Y312500D01*
X55867Y312900D01*
X56400Y313033D01*
X56933Y312900D01*
X57333Y312567D01*
X57533Y311967D01*
Y310367D01*
G01X59200Y317533D02*
Y314867D01*
X55200D01*
Y317533D01*
G01X57133Y316467D02*
Y314867D01*
G01X59200Y319367D02*
X55200D01*
Y321033D01*
X55400Y321567D01*
X55667Y321900D01*
X56200Y322033D01*
X56733Y321900D01*
X57067Y321500D01*
X57267Y321033D01*
Y319367D01*
G01Y321033D02*
X59200Y322033D01*
G01X55200Y329700D02*
X59200D01*
G01X55200Y328167D02*
Y331233D01*
G01X59200Y332867D02*
X55200D01*
Y334533D01*
X55400Y335067D01*
X55667Y335400D01*
X56200Y335533D01*
X56733Y335400D01*
X57067Y335000D01*
X57267Y334533D01*
Y332867D01*
G01Y334533D02*
X59200Y335533D01*
G01Y337033D02*
X55200Y338700D01*
X59200Y340367D01*
G01X57800Y339767D02*
Y337633D01*
G01X59200Y343200D02*
X57400D01*
X55200Y341867D01*
G01Y344533D02*
X57400Y343200D01*
G01X198500Y300167D02*
X202500D01*
Y302833D01*
G01Y306000D02*
X202433Y305467D01*
X202167Y305000D01*
X201767Y304600D01*
X201300Y304333D01*
X200767Y304200D01*
X200233D01*
X199700Y304333D01*
X199233Y304600D01*
X198833Y305000D01*
X198567Y305467D01*
X198500Y306000D01*
X198567Y306533D01*
X198833Y307000D01*
X199233Y307400D01*
X199700Y307667D01*
X200233Y307800D01*
X200767D01*
X201300Y307667D01*
X201767Y307400D01*
X202167Y307000D01*
X202433Y306533D01*
X202500Y306000D01*
G01X198500Y308500D02*
X202500Y309433D01*
X198500Y310500D01*
X202500Y311567D01*
X198500Y312500D01*
G01X202500Y316333D02*
Y313667D01*
X198500D01*
Y316333D01*
G01X200433Y315267D02*
Y313667D01*
G01X202500Y318167D02*
X198500D01*
Y319833D01*
X198700Y320367D01*
X198967Y320700D01*
X199500Y320833D01*
X200033Y320700D01*
X200367Y320300D01*
X200567Y319833D01*
Y318167D01*
G01Y319833D02*
X202500Y320833D01*
G01X198500Y328500D02*
X202500D01*
G01X198500Y326967D02*
Y330033D01*
G01X202500Y331667D02*
X198500D01*
Y333333D01*
X198700Y333867D01*
X198967Y334200D01*
X199500Y334333D01*
X200033Y334200D01*
X200367Y333800D01*
X200567Y333333D01*
Y331667D01*
G01Y333333D02*
X202500Y334333D01*
G01Y335833D02*
X198500Y337500D01*
X202500Y339167D01*
G01X201100Y338567D02*
Y336433D01*
G01X202500Y342000D02*
X200700D01*
X198500Y340667D01*
G01Y343333D02*
X200700Y342000D01*
G54D13*
G01X-430254Y-152763D02*
Y-135263D01*
G01X-421958D02*
X-430254Y-146055D01*
G01X-420648Y-152763D02*
X-426543Y-141097D01*
G01X-412973Y-152763D02*
Y-135263D01*
X-402929Y-152763D01*
Y-135263D01*
G01X-390451Y-152763D02*
X-392198Y-152471D01*
X-393726Y-151305D01*
X-395036Y-149555D01*
X-395910Y-147513D01*
X-396346Y-145180D01*
Y-142846D01*
X-395910Y-140513D01*
X-395036Y-138471D01*
X-393726Y-136722D01*
X-392198Y-135555D01*
X-390451Y-135263D01*
X-388705Y-135555D01*
X-387176Y-136722D01*
X-385866Y-138471D01*
X-384992Y-140513D01*
X-384556Y-142846D01*
Y-145180D01*
X-384992Y-147513D01*
X-385866Y-149555D01*
X-387176Y-151305D01*
X-388705Y-152471D01*
X-390451Y-152763D01*
G01X-377536D02*
X-368366Y-135263D01*
G01X-377536D02*
X-368366Y-152763D01*
G01X-362001Y-158596D02*
X-348901D01*
G01X-342099Y-152763D02*
Y-135263D01*
X-333803D01*
G01X-336859Y-143721D02*
X-342099D01*
G01X-325910Y-152763D02*
X-320451Y-135263D01*
X-314992Y-152763D01*
G01X-316958Y-146638D02*
X-323945D01*
G01X-307973Y-152763D02*
Y-135263D01*
X-297929Y-152763D01*
Y-135263D01*
G01X-263148Y-136722D02*
X-264458Y-135846D01*
X-265986Y-135263D01*
X-267733D01*
X-269698Y-136138D01*
X-271226Y-137596D01*
X-272318Y-139347D01*
X-273191Y-142263D01*
X-273410Y-144888D01*
X-272973Y-147513D01*
X-272318Y-149263D01*
X-271008Y-151013D01*
X-269479Y-152180D01*
X-267951Y-152763D01*
X-266423D01*
X-264894Y-152180D01*
X-263584Y-151305D01*
X-262492Y-150139D01*
G01X-250451Y-152763D02*
X-252198Y-152471D01*
X-253726Y-151305D01*
X-255036Y-149555D01*
X-255910Y-147513D01*
X-256346Y-145180D01*
Y-142846D01*
X-255910Y-140513D01*
X-255036Y-138471D01*
X-253726Y-136722D01*
X-252198Y-135555D01*
X-250451Y-135263D01*
X-248705Y-135555D01*
X-247176Y-136722D01*
X-245866Y-138471D01*
X-244992Y-140513D01*
X-244556Y-142846D01*
Y-145180D01*
X-244992Y-147513D01*
X-245866Y-149555D01*
X-247176Y-151305D01*
X-248705Y-152471D01*
X-250451Y-152763D01*
G01X-237973D02*
Y-135263D01*
X-227929Y-152763D01*
Y-135263D01*
G01X-215451D02*
Y-152763D01*
G01X-220473Y-135263D02*
X-210429D01*
G01X-202318Y-152763D02*
Y-135263D01*
X-196859D01*
X-195113Y-136138D01*
X-194021Y-137305D01*
X-193584Y-139638D01*
X-194021Y-141972D01*
X-195331Y-143430D01*
X-196859Y-144305D01*
X-202318D01*
G01X-196859D02*
X-193584Y-152763D01*
G01X-180451D02*
X-182198Y-152471D01*
X-183726Y-151305D01*
X-185036Y-149555D01*
X-185910Y-147513D01*
X-186346Y-145180D01*
Y-142846D01*
X-185910Y-140513D01*
X-185036Y-138471D01*
X-183726Y-136722D01*
X-182198Y-135555D01*
X-180451Y-135263D01*
X-178705Y-135555D01*
X-177176Y-136722D01*
X-175866Y-138471D01*
X-174992Y-140513D01*
X-174556Y-142846D01*
Y-145180D01*
X-174992Y-147513D01*
X-175866Y-149555D01*
X-177176Y-151305D01*
X-178705Y-152471D01*
X-180451Y-152763D01*
G01X-167318Y-135263D02*
Y-152763D01*
X-158584D01*
G01X-126205Y-143430D02*
X-125331Y-142555D01*
X-124676Y-141097D01*
X-124239Y-139054D01*
X-124676Y-137305D01*
X-125549Y-136138D01*
X-127078Y-135263D01*
X-132973D01*
Y-152763D01*
X-125768D01*
X-124239Y-151597D01*
X-123366Y-149846D01*
X-122929Y-147805D01*
X-123366Y-145763D01*
X-124676Y-144013D01*
X-126205Y-143430D01*
X-132973D01*
G01X-110451Y-152763D02*
X-112198Y-152471D01*
X-113726Y-151305D01*
X-115036Y-149555D01*
X-115910Y-147513D01*
X-116346Y-145180D01*
Y-142846D01*
X-115910Y-140513D01*
X-115036Y-138471D01*
X-113726Y-136722D01*
X-112198Y-135555D01*
X-110451Y-135263D01*
X-108705Y-135555D01*
X-107176Y-136722D01*
X-105866Y-138471D01*
X-104992Y-140513D01*
X-104556Y-142846D01*
Y-145180D01*
X-104992Y-147513D01*
X-105866Y-149555D01*
X-107176Y-151305D01*
X-108705Y-152471D01*
X-110451Y-152763D01*
G01X-98410D02*
X-92951Y-135263D01*
X-87492Y-152763D01*
G01X-89458Y-146638D02*
X-96445D01*
G01X-79818Y-152763D02*
Y-135263D01*
X-74359D01*
X-72613Y-136138D01*
X-71521Y-137305D01*
X-71084Y-139638D01*
X-71521Y-141972D01*
X-72831Y-143430D01*
X-74359Y-144305D01*
X-79818D01*
G01X-74359D02*
X-71084Y-152763D01*
G01X-62754D02*
Y-135263D01*
X-58388D01*
X-56641Y-136138D01*
X-55331Y-137305D01*
X-54239Y-139054D01*
X-53366Y-141097D01*
X-53148Y-144013D01*
X-53366Y-146930D01*
X-54239Y-148972D01*
X-55331Y-150722D01*
X-56641Y-151888D01*
X-58388Y-152763D01*
X-62754D01*
G01X-282378Y-107763D02*
Y-90263D01*
X-276701Y-104846D01*
X-271024Y-90263D01*
Y-107763D01*
G01X-259201D02*
X-260511Y-107471D01*
X-261821Y-106305D01*
X-262695Y-104263D01*
X-263131Y-101930D01*
X-262695Y-99596D01*
X-261821Y-97555D01*
X-260511Y-96388D01*
X-259201Y-96097D01*
X-257891Y-96388D01*
X-256581Y-97555D01*
X-255708Y-99596D01*
X-255489Y-101930D01*
X-255708Y-104263D01*
X-256581Y-106305D01*
X-257891Y-107471D01*
X-259201Y-107763D01*
G01X-237771Y-90263D02*
Y-107763D01*
G01Y-105139D02*
X-238644Y-106597D01*
X-239955Y-107471D01*
X-241483Y-107763D01*
X-243229Y-107180D01*
X-244539Y-105722D01*
X-245413Y-103972D01*
X-245631Y-101930D01*
X-245413Y-99888D01*
X-244539Y-98138D01*
X-243229Y-96680D01*
X-241483Y-96097D01*
X-239955Y-96388D01*
X-238863Y-96972D01*
X-237771Y-98138D01*
G01X-227476Y-99888D02*
X-220489D01*
X-221144Y-97846D01*
X-222236Y-96680D01*
X-223764Y-96097D01*
X-225293Y-96388D01*
X-226603Y-97263D01*
X-227476Y-99305D01*
X-227913Y-101055D01*
Y-102805D01*
X-227476Y-104555D01*
X-226384Y-106305D01*
X-225074Y-107471D01*
X-223546Y-107763D01*
X-222018Y-107180D01*
X-220489Y-105430D01*
G01X-206701Y-107763D02*
Y-90263D01*
G01X-242126Y15000D02*
G03X-227126Y0I15000J0D01*
G01X-242126Y1953504D02*
Y15000D01*
G01X-215453Y19685D02*
G03I-6988J0D01*
G01X-84646Y0D02*
X-227126D01*
G01X-215453Y19685D02*
G03I-6988J0D01*
G01D02*
G03I-6988J0D01*
G01X-227126Y1968504D02*
G03X-242126Y1953504I0J-15000D01*
G01X-215453Y1948819D02*
G03I-6988J0D01*
G01X-84638Y1968504D02*
X-227126D01*
G01X-215453Y1948819D02*
G03I-6988J0D01*
G01D02*
G03I-6988J0D01*
G01X-222441Y39370D02*
G03X-214567Y31496I7874J0D01*
G01X-206693D02*
X-214567D01*
G01X-175984D02*
X-84646D01*
G01X-206693D02*
G03Y39370I0J3937D01*
G01X-175984D02*
G03Y31496I0J-3937D01*
G01X-206693D02*
X-214567D01*
G01X-84646Y0D02*
X-199567D01*
G01X-175984Y31496D02*
X-84646D01*
G01X-206693D02*
G03Y39370I0J3937D01*
G01X-175984D02*
G03Y31496I0J-3937D01*
G01X-222441Y169326D02*
Y39370D01*
G01X-214567Y43307D02*
G03X-210630Y39370I3937J0D01*
G01X-214567Y43307D02*
G03X-210630Y39370I3937J0D01*
G01X-80709D02*
X-210630D01*
G01X-80709D02*
X-210630D01*
G01X-214567Y43307D02*
Y1925197D01*
G01Y43307D02*
Y1925197D01*
G01Y149606D02*
Y43307D01*
G01Y149606D02*
Y43272D01*
G01Y169326D02*
G03X-222441I-3937J0D01*
G01X-214567D02*
G03X-222441I-3937J0D01*
G01X-214567Y1807087D02*
Y161417D01*
G01Y1807087D02*
Y161417D01*
G01X-222441Y436255D02*
Y200034D01*
G01D02*
G03X-214567I3937J0D01*
G01X-222441D02*
G03X-214567I3937J0D01*
G01Y436255D02*
G03X-222441I-3937J0D01*
G01X-214567D02*
G03X-222441I-3937J0D01*
G01Y703184D02*
Y466963D01*
G01D02*
G03X-214567I3937J0D01*
G01X-222441D02*
G03X-214567I3937J0D01*
G01X-222441Y970901D02*
Y733892D01*
G01X-214567Y703184D02*
G03X-222441I-3937J0D01*
G01Y733892D02*
G03X-214567I3937J0D01*
G01Y703184D02*
G03X-222441I-3937J0D01*
G01Y733892D02*
G03X-214567I3937J0D01*
G01X-222441Y1234681D02*
Y997672D01*
G01X-214567Y970901D02*
G03X-222441I-3937J0D01*
G01Y997672D02*
G03X-214567I3937J0D01*
G01Y970901D02*
G03X-222441I-3937J0D01*
G01Y997672D02*
G03X-214567I3937J0D01*
G01X-222441Y1265389D02*
G03X-214567I3937J0D01*
G01Y1234681D02*
G03X-222441I-3937J0D01*
G01Y1265389D02*
G03X-214567I3937J0D01*
G01Y1234681D02*
G03X-222441I-3937J0D01*
G01Y1501610D02*
Y1265389D01*
G01X-214567Y1501610D02*
G03X-222441I-3937J0D01*
G01X-214567D02*
G03X-222441I-3937J0D01*
G01Y1768539D02*
Y1532318D01*
G01D02*
G03X-214567I3937J0D01*
G01X-222441D02*
G03X-214567I3937J0D01*
G01Y1768539D02*
G03X-222441I-3937J0D01*
G01X-214567D02*
G03X-222441I-3937J0D01*
G01Y1799247D02*
G03X-214567I3937J0D01*
G01X-222441D02*
G03X-214567I3937J0D01*
G01X-222441Y1929134D02*
Y1799247D01*
G01X-214567Y1818898D02*
Y1925231D01*
G01Y1818898D02*
Y1925231D01*
G01X-210630Y1929134D02*
G03X-214567Y1925197I0J-3937D01*
G01X-210630Y1929134D02*
G03X-214567Y1925197I0J-3937D01*
G01Y1937008D02*
G03X-222441Y1929134I0J-7874D01*
G01X-210630D02*
X-80709D01*
G01X-210630D02*
X-80709D01*
G01X-175984Y1937008D02*
X-84638D01*
G01X-214567D02*
X-206693D01*
G01X-175984D02*
G03Y1929134I0J-3937D01*
G01X-206693D02*
G03Y1937008I0J3937D01*
G01X-84638Y1968504D02*
X-199567D01*
G01X-175984Y1937008D02*
X-84638D01*
G01X-214567D02*
X-206693D01*
G01X-175984D02*
G03Y1929134I0J-3937D01*
G01X-206693D02*
G03Y1937008I0J3937D01*
G01X-76772Y3937D02*
G03X-72835Y0I3937J0D01*
G01X-76772Y35433D02*
G03X-80709Y39370I-3937J0D01*
G01X-76772Y35433D02*
G03X-80709Y39370I-3937J0D01*
G01X-76772Y3937D02*
G03X-72835Y0I3937J0D01*
G01X-76772Y3937D02*
Y35433D01*
G01Y3937D02*
Y35433D01*
G01Y3937D02*
G03X-72835Y0I3937J0D01*
G01X-84646Y7874D02*
Y0D01*
G01X-76772Y7874D02*
G03X-84646I-3937J0D01*
G01Y31496D02*
G03X-76772I3937J0D01*
G01Y3937D02*
G03X-72835Y0I3937J0D01*
G01X-84646Y7874D02*
Y0D01*
G01X-76772Y7874D02*
G03X-84646I-3937J0D01*
G01Y31496D02*
G03X-76772I3937J0D01*
G01X-76763Y1937008D02*
G03X-84638I-3937J0D01*
G01X-80709Y1929134D02*
G03X-76772Y1933071I0J3937D01*
G01X-80709Y1929134D02*
G03X-76772Y1933071I0J3937D01*
G01X-72835Y1968504D02*
G03X-76772Y1964567I0J-3937D01*
G01X-72835Y1968504D02*
G03X-76772Y1964567I0J-3937D01*
G01Y1933071D02*
Y1964567D01*
G01Y1933071D02*
Y1964567D01*
G01X-72835Y1968504D02*
G03X-76772Y1964567I0J-3937D01*
G01X-84638Y1960889D02*
Y1968504D01*
G01Y1960889D02*
G03X-76763I3938J0D01*
G01X-72835Y1968504D02*
G03X-76772Y1964567I0J-3937D01*
G01X-84638Y1960889D02*
Y1968504D01*
G01Y1960889D02*
G03X-76763I3938J0D01*
G01X-11811Y0D02*
X-72835D01*
G01X-11811D02*
X-72835D01*
G01D02*
X-11811D01*
G01X-72835D02*
X-11811D01*
G01X-72835Y1968504D02*
X-11811D01*
G01X-72835D02*
X-11811D01*
G01D02*
X-72835D01*
G01X-11811D02*
X-72835D01*
G01X-901Y-152763D02*
Y-135263D01*
X-3521Y-138763D01*
G01Y-152763D02*
X1719D01*
G01X12451Y-138180D02*
X13761Y-136430D01*
X15289Y-135555D01*
X17036Y-135263D01*
X19219Y-135846D01*
X20747Y-137305D01*
X21184Y-139054D01*
X20966Y-140805D01*
X20092Y-142263D01*
X15726Y-145180D01*
X13761Y-147221D01*
X12451Y-150139D01*
X12014Y-152763D01*
X21184D01*
G01X36719D02*
Y-135263D01*
X28640Y-147805D01*
X39558D01*
G01X46796Y-149263D02*
X48105Y-151305D01*
X49852Y-152471D01*
X51817Y-152763D01*
X53564Y-152471D01*
X55311Y-151013D01*
X56402Y-149263D01*
X56621Y-147513D01*
X56184Y-145472D01*
X54656Y-144013D01*
X53127Y-143430D01*
X51162D01*
G01X53127D02*
X54437Y-142555D01*
X55529Y-141097D01*
X55966Y-139347D01*
X55529Y-137596D01*
X54437Y-136138D01*
X52472Y-135263D01*
X50507Y-135555D01*
X48542Y-136722D01*
G01X64296Y-149263D02*
X65605Y-151305D01*
X67352Y-152471D01*
X69317Y-152763D01*
X71064Y-152471D01*
X72811Y-151013D01*
X73902Y-149263D01*
X74121Y-147513D01*
X73684Y-145472D01*
X72156Y-144013D01*
X70627Y-143430D01*
X68662D01*
G01X70627D02*
X71937Y-142555D01*
X73029Y-141097D01*
X73466Y-139347D01*
X73029Y-137596D01*
X71937Y-136138D01*
X69972Y-135263D01*
X68007Y-135555D01*
X66042Y-136722D01*
G01X-14018Y-107763D02*
Y-90263D01*
X-8778D01*
X-7031Y-91138D01*
X-5721Y-93180D01*
X-5284Y-95513D01*
X-5721Y-97846D01*
X-6813Y-99596D01*
X-8778Y-100472D01*
X-14018D01*
G01X12652Y-91722D02*
X11342Y-90846D01*
X9814Y-90263D01*
X8067D01*
X6102Y-91138D01*
X4574Y-92596D01*
X3482Y-94347D01*
X2609Y-97263D01*
X2390Y-99888D01*
X2827Y-102513D01*
X3482Y-104263D01*
X4792Y-106013D01*
X6321Y-107180D01*
X7849Y-107763D01*
X9377D01*
X10906Y-107180D01*
X12216Y-106305D01*
X13308Y-105139D01*
G01X27095Y-98430D02*
X27969Y-97555D01*
X28624Y-96097D01*
X29061Y-94054D01*
X28624Y-92305D01*
X27751Y-91138D01*
X26222Y-90263D01*
X20327D01*
Y-107763D01*
X27532D01*
X29061Y-106597D01*
X29934Y-104846D01*
X30371Y-102805D01*
X29934Y-100763D01*
X28624Y-99013D01*
X27095Y-98430D01*
X20327D01*
G01X36299Y-113596D02*
X49399D01*
G01X55327Y-107763D02*
Y-90263D01*
X65371Y-107763D01*
Y-90263D01*
G01X77849Y-107763D02*
X76102Y-107471D01*
X74574Y-106305D01*
X73264Y-104555D01*
X72390Y-102513D01*
X71954Y-100180D01*
Y-97846D01*
X72390Y-95513D01*
X73264Y-93471D01*
X74574Y-91722D01*
X76102Y-90555D01*
X77849Y-90263D01*
X79595Y-90555D01*
X81124Y-91722D01*
X82434Y-93471D01*
X83308Y-95513D01*
X83744Y-97846D01*
Y-100180D01*
X83308Y-102513D01*
X82434Y-104555D01*
X81124Y-106305D01*
X79595Y-107471D01*
X77849Y-107763D01*
G01X-11811Y0D02*
G03X-7874Y3937I0J3937D01*
G01X-11811Y0D02*
G03X-7874Y3937I0J3937D01*
G01Y43110D02*
Y3937D01*
G01Y43110D02*
Y3937D01*
G01X0D02*
G03X3937Y0I3937J0D01*
G01X0Y3937D02*
G03X3937Y0I3937J0D01*
G01X0Y3937D02*
Y43110D01*
G01Y3937D02*
Y43110D01*
G01X64961Y0D02*
X3937D01*
G01X64961D02*
X3937D01*
G01X0Y3937D02*
G03X3937Y0I3937J0D01*
G01X0Y1964567D02*
Y3937D01*
G01X3937Y0D02*
X64961D01*
G01X-7874Y3937D02*
Y1964567D01*
G01X-11811Y0D02*
G03X-7874Y3937I0J3937D01*
G01X0Y11811D02*
G03X-7874I-3937J0D01*
G01X0Y3937D02*
G03X3937Y0I3937J0D01*
G01X0Y1964567D02*
Y3937D01*
G01X3937Y0D02*
X64961D01*
G01X-7874Y3937D02*
Y1964567D01*
G01X-11811Y0D02*
G03X-7874Y3937I0J3937D01*
G01X0Y11811D02*
G03X-7874I-3937J0D01*
G01Y93110D02*
Y43110D01*
G01Y93110D02*
Y43110D01*
G01X0D02*
Y93110D01*
G01Y43110D02*
Y93110D01*
G01X-7874Y42520D02*
G03X0I3937J0D01*
G01X-7874D02*
G03X0I3937J0D01*
G01X-7874Y214764D02*
Y93110D01*
G01Y214764D02*
Y93110D01*
G01X0D02*
Y214764D01*
G01Y93110D02*
Y214764D01*
G01X-7874Y226968D02*
Y214764D01*
G01Y226968D02*
Y214764D01*
G01Y342461D02*
Y226968D01*
G01Y342461D02*
Y226968D01*
G01X0Y226969D02*
Y342461D01*
G01Y226969D02*
Y342461D01*
G01Y214764D02*
Y226969D01*
G01Y214764D02*
Y226969D01*
G01Y278740D02*
G03X-7874I-3937J0D01*
G01X0D02*
G03X-7874I-3937J0D01*
G01Y354665D02*
Y342461D01*
G01Y354665D02*
Y342461D01*
G01X0D02*
Y354665D01*
G01Y342461D02*
Y354665D01*
G01X-7874Y309449D02*
G03X0I3937J0D01*
G01X-7874D02*
G03X0I3937J0D01*
G01X-7874Y476339D02*
Y354665D01*
G01Y476339D02*
Y354665D01*
G01X0D02*
Y476339D01*
G01Y354665D02*
Y476339D01*
G01X-7874Y526339D02*
Y476339D01*
G01Y526339D02*
Y476339D01*
G01X0D02*
Y526339D01*
G01Y476339D02*
Y526339D01*
G01X-7874Y736181D02*
Y526339D01*
G01Y736181D02*
Y526339D01*
G01X0D02*
Y736181D01*
G01Y526339D02*
Y736181D01*
G01Y545669D02*
G03X-7874I-3937J0D01*
G01X0D02*
G03X-7874I-3937J0D01*
G01Y576378D02*
G03X0I3937J0D01*
G01X-7874D02*
G03X0I3937J0D01*
G01X-7874Y786181D02*
Y736181D01*
G01Y786181D02*
Y736181D01*
G01X0D02*
Y786181D01*
G01Y736181D02*
Y786181D01*
G01X-7874Y907815D02*
Y786181D01*
G01Y907815D02*
Y786181D01*
G01X0D02*
Y907815D01*
G01Y786181D02*
Y907815D01*
G01Y831496D02*
G03X-7874I-3937J0D01*
G01X0D02*
G03X-7874I-3937J0D01*
G01Y862205D02*
G03X0I3937J0D01*
G01X-7874D02*
G03X0I3937J0D01*
G01X-7874Y920020D02*
Y907815D01*
G01Y920020D02*
Y907815D01*
G01Y1048484D02*
Y920020D01*
G01Y1048484D02*
Y920020D01*
G01X0D02*
Y1048484D01*
G01Y920020D02*
Y1048484D01*
G01Y907815D02*
Y920020D01*
G01Y907815D02*
Y920020D01*
G01X-7874Y1060689D02*
Y1048484D01*
G01Y1060689D02*
Y1048484D01*
G01X0D02*
Y1060689D01*
G01Y1048484D02*
Y1060689D01*
G01X-7874Y1182323D02*
Y1060689D01*
G01Y1182323D02*
Y1060689D01*
G01X0D02*
Y1182323D01*
G01Y1060689D02*
Y1182323D01*
G01Y1106299D02*
G03X-7874I-3937J0D01*
G01X0D02*
G03X-7874I-3937J0D01*
G01Y1137008D02*
G03X0I3937J0D01*
G01X-7874D02*
G03X0I3937J0D01*
G01X-7874Y1232323D02*
Y1182323D01*
G01Y1232323D02*
Y1182323D01*
G01X0D02*
Y1232323D01*
G01Y1182323D02*
Y1232323D01*
G01X-7874Y1442165D02*
Y1232323D01*
G01Y1442165D02*
Y1232323D01*
G01X0D02*
Y1442165D01*
G01Y1232323D02*
Y1442165D01*
G01Y1392126D02*
G03X-7874I-3937J0D01*
G01X0D02*
G03X-7874I-3937J0D01*
G01Y1492165D02*
Y1442165D01*
G01Y1492165D02*
Y1442165D01*
G01X0D02*
Y1492165D01*
G01Y1442165D02*
Y1492165D01*
G01X-7874Y1422835D02*
G03X0I3937J0D01*
G01X-7874D02*
G03X0I3937J0D01*
G01X-7874Y1613839D02*
Y1492165D01*
G01Y1613839D02*
Y1492165D01*
G01X0D02*
Y1613839D01*
G01Y1492165D02*
Y1613839D01*
G01X-7874Y1626043D02*
Y1613839D01*
G01Y1626043D02*
Y1613839D01*
G01X0D02*
Y1626043D01*
G01Y1613839D02*
Y1626043D01*
G01X-7874Y1741535D02*
Y1626043D01*
G01Y1741535D02*
Y1626043D01*
G01X0D02*
Y1741535D01*
G01Y1626043D02*
Y1741535D01*
G01Y1659055D02*
G03X-7874I-3937J0D01*
G01X0D02*
G03X-7874I-3937J0D01*
G01Y1689764D02*
G03X0I3937J0D01*
G01X-7874D02*
G03X0I3937J0D01*
G01X-7874Y1753740D02*
Y1741535D01*
G01Y1753740D02*
Y1741535D01*
G01Y1875394D02*
Y1753740D01*
G01Y1875394D02*
Y1753740D01*
G01X0D02*
Y1875394D01*
G01Y1753740D02*
Y1875394D01*
G01Y1741535D02*
Y1753740D01*
G01Y1741535D02*
Y1753740D01*
G01X-7874Y1925394D02*
Y1875394D01*
G01Y1925394D02*
Y1875394D01*
G01X0D02*
Y1925394D01*
G01Y1875394D02*
Y1925394D01*
G01X-7874Y1964567D02*
Y1925394D01*
G01Y1964567D02*
Y1925394D01*
G01X0D02*
Y1964567D01*
G01Y1925394D02*
Y1964567D01*
G01Y1925984D02*
G03X-7874I-3937J0D01*
G01X0D02*
G03X-7874I-3937J0D01*
G01Y1964567D02*
G03X-11811Y1968504I-3937J0D01*
G01X-7874Y1964567D02*
G03X-11811Y1968504I-3937J0D01*
G01X3937D02*
G03X0Y1964567I0J-3937D01*
G01X3937Y1968504D02*
G03X0Y1964567I0J-3937D01*
G01X3937Y1968504D02*
X64961D01*
G01X3937D02*
X64961D01*
G01X3937D02*
G03X0Y1964567I0J-3937D01*
G01X64961Y1968504D02*
X3937D01*
G01X-7874Y1964567D02*
G03X-11811Y1968504I-3937J0D01*
G01X-7874Y1956693D02*
G03X0I3937J0D01*
G01X3937Y1968504D02*
G03X0Y1964567I0J-3937D01*
G01X64961Y1968504D02*
X3937D01*
G01X-7874Y1964567D02*
G03X-11811Y1968504I-3937J0D01*
G01X-7874Y1956693D02*
G03X0I3937J0D01*
G01X168110Y31496D02*
X76763D01*
G01X72835Y39370D02*
G03X68898Y35433I0J-3937D01*
G01X72835Y39370D02*
G03X68898Y35433I0J-3937D01*
G01X64961Y0D02*
G03X68898Y3937I0J3937D01*
G01X64961Y0D02*
G03X68898Y3937I0J3937D01*
G01Y35433D02*
Y3937D01*
G01Y35433D02*
Y3937D01*
G01X72835Y39370D02*
G03X68898Y35433I0J-3937D01*
G01Y3937D02*
Y35485D01*
G01X64961Y0D02*
G03X68898Y3937I0J3937D01*
G01X76763D02*
G03X80700Y0I3937J0D01*
G01X76763Y7615D02*
Y3937D01*
G01X168110Y31496D02*
X76763D01*
G01Y7615D02*
G03X68889I-3937J0D01*
G01Y31496D02*
G03X76763I3937J0D01*
G01X72835Y39370D02*
G03X68898Y35433I0J-3937D01*
G01Y3937D02*
Y35485D01*
G01X64961Y0D02*
G03X68898Y3937I0J3937D01*
G01X76763D02*
G03X80700Y0I3937J0D01*
G01X76763Y7615D02*
Y3937D01*
G01X168110Y31496D02*
X76763D01*
G01Y7615D02*
G03X68889I-3937J0D01*
G01Y31496D02*
G03X76763I3937J0D01*
G01X202756Y39370D02*
X72835D01*
G01X202756D02*
X72835D01*
G01D02*
X202756D01*
G01X72835D02*
X202756D01*
G01X68898Y1964567D02*
G03X64961Y1968504I-3937J0D01*
G01X68898Y1933071D02*
G03X72835Y1929134I3937J0D01*
G01X68898Y1933071D02*
G03X72835Y1929134I3937J0D01*
G01X68898Y1964567D02*
G03X64961Y1968504I-3937J0D01*
G01X72835Y1929134D02*
X202756D01*
G01X72835D02*
X202756D01*
G01X68898Y1964567D02*
Y1933071D01*
G01Y1964567D02*
Y1933071D01*
G01Y1964567D02*
G03X64961Y1968504I-3937J0D01*
G01X68898Y1933071D02*
Y1964567D01*
G01Y1933071D02*
G03X72835Y1929134I3937J0D01*
G01X202756D02*
X72835D01*
G01X80709Y1968504D02*
G03X76772Y1964567I0J-3937D01*
G01Y1960630D02*
Y1964567D01*
G01X168110Y1937008D02*
X76772D01*
G01X68898Y1960630D02*
G03X76772I3937J0D01*
G01Y1937008D02*
G03X68898I-3937J0D01*
G01Y1964567D02*
G03X64961Y1968504I-3937J0D01*
G01X68898Y1933071D02*
Y1964567D01*
G01Y1933071D02*
G03X72835Y1929134I3937J0D01*
G01X202756D02*
X72835D01*
G01X80709Y1968504D02*
G03X76772Y1964567I0J-3937D01*
G01Y1960630D02*
Y1964567D01*
G01X168110Y1937008D02*
X76772D01*
G01X68898Y1960630D02*
G03X76772I3937J0D01*
G01Y1937008D02*
G03X68898I-3937J0D01*
G01X128690Y-90263D02*
X134149Y-107763D01*
X139608Y-90263D01*
G01X156016Y-107763D02*
X147282D01*
Y-90263D01*
X156016D01*
G01X152522Y-98721D02*
X147282D01*
G01X164782Y-107763D02*
Y-90263D01*
X170241D01*
X171987Y-91138D01*
X173079Y-92305D01*
X173516Y-94638D01*
X173079Y-96972D01*
X171769Y-98430D01*
X170241Y-99305D01*
X164782D01*
G01X170241D02*
X173516Y-107763D01*
G01X186649Y-108346D02*
X186212Y-108055D01*
Y-107471D01*
X186649Y-107180D01*
X187086Y-107471D01*
Y-108055D01*
X186649Y-108346D01*
G01X80700Y0D02*
X340551D01*
G01X80700D02*
X340551D01*
G01X118011Y1968504D02*
X142520D01*
G01X109377D02*
X110137D01*
G01X109377D02*
X80709D01*
G01X110137D02*
G03X118011I3937J0D01*
G01X109377D02*
X80709D01*
G01X110137D02*
G03X118011I3937J0D01*
G01X151649Y-152763D02*
Y-135263D01*
X149029Y-138763D01*
G01Y-152763D02*
X154269D01*
G01X163472D02*
Y-135263D01*
X169149Y-149846D01*
X174826Y-135263D01*
Y-152763D01*
G01X168110Y31496D02*
G03Y39370I0J3937D01*
G01Y31496D02*
G03Y39370I0J3937D01*
G01X340559Y1968504D02*
X142520D01*
G01X168110Y1929134D02*
G03Y1937008I0J3937D01*
G01X340559Y1968504D02*
X142520D01*
G01X168110Y1929134D02*
G03Y1937008I0J3937D01*
G01X222441Y31496D02*
X198819D01*
G01X222441D02*
G03Y39370I0J3937D01*
G01X198819D02*
G03Y31496I0J-3937D01*
G01X222441D02*
X198819D01*
G01X222441D02*
G03Y39370I0J3937D01*
G01X198819D02*
G03Y31496I0J-3937D01*
G01X214567Y161417D02*
Y43307D01*
G01X202756Y39370D02*
G03X206693Y43307I0J3937D01*
G01X202756Y39370D02*
G03X206693Y43307I0J3937D01*
G01Y1925197D02*
Y43307D01*
G01Y1925197D02*
Y43307D01*
G01X202756Y39370D02*
G03X206693Y43307I0J3937D01*
G01X218504Y39370D02*
X348425D01*
G01X214567Y43307D02*
G03X218504Y39370I3937J0D01*
G01X202756D02*
G03X206693Y43307I0J3937D01*
G01X218504Y39370D02*
X348425D01*
G01X214567Y43307D02*
G03X218504Y39370I3937J0D01*
G01X206693Y161417D02*
Y1807087D01*
G01X214567D02*
Y161417D01*
G01Y169291D02*
G03X206693I-3937J0D01*
G01Y161417D02*
Y1807087D01*
G01X214567D02*
Y161417D01*
G01Y169291D02*
G03X206693I-3937J0D01*
G01Y200000D02*
G03X214567I3937J0D01*
G01X206693D02*
G03X214567I3937J0D01*
G01Y436220D02*
G03X206693I-3937J0D01*
G01X214567D02*
G03X206693I-3937J0D01*
G01Y466929D02*
G03X214567I3937J0D01*
G01X206693D02*
G03X214567I3937J0D01*
G01Y703149D02*
G03X206693I-3937J0D01*
G01Y733858D02*
G03X214567I3937J0D01*
G01Y703149D02*
G03X206693I-3937J0D01*
G01Y733858D02*
G03X214567I3937J0D01*
G01Y970867D02*
G03X206693I-3937J0D01*
G01Y997637D02*
G03X214567I3937J0D01*
G01Y970867D02*
G03X206693I-3937J0D01*
G01Y997637D02*
G03X214567I3937J0D01*
G01X206693Y1265355D02*
G03X214567I3937J0D01*
G01Y1234646D02*
G03X206693I-3937J0D01*
G01Y1265355D02*
G03X214567I3937J0D01*
G01Y1234646D02*
G03X206693I-3937J0D01*
G01X214567Y1501575D02*
G03X206693I-3937J0D01*
G01X214567D02*
G03X206693I-3937J0D01*
G01Y1532284D02*
G03X214567I3937J0D01*
G01X206693D02*
G03X214567I3937J0D01*
G01Y1768504D02*
G03X206693I-3937J0D01*
G01X214567D02*
G03X206693I-3937J0D01*
G01X214567Y1807087D02*
Y1925197D01*
G01X206693Y1799213D02*
G03X214567I3937J0D01*
G01X206693D02*
G03X214567I3937J0D01*
G01X206693Y1925197D02*
G03X202756Y1929134I-3937J0D01*
G01X206693Y1925197D02*
G03X202756Y1929134I-3937J0D01*
G01X206693Y1925197D02*
G03X202756Y1929134I-3937J0D01*
G01X218504D02*
G03X214567Y1925197I0J-3937D01*
G01X206693D02*
G03X202756Y1929134I-3937J0D01*
G01X218504D02*
G03X214567Y1925197I0J-3937D01*
G01X348425Y1929134D02*
X218504D01*
G01X198819Y1937008D02*
X222441D01*
G01X198819D02*
G03Y1929134I0J-3937D01*
G01X222441D02*
G03Y1937008I0J3937D01*
G01X348425Y1929134D02*
X218504D01*
G01X198819Y1937008D02*
X222441D01*
G01X198819D02*
G03Y1929134I0J-3937D01*
G01X222441D02*
G03Y1937008I0J3937D01*
G01X242549Y-135263D02*
X245605Y-152763D01*
X249099Y-135263D01*
X252592Y-152763D01*
X255649Y-135263D01*
G01X262014Y-150430D02*
X263761Y-151888D01*
X265726Y-152763D01*
X267472D01*
X269219Y-151888D01*
X270529Y-150430D01*
X271184Y-148388D01*
X270747Y-146347D01*
X269656Y-144596D01*
X267691Y-143430D01*
X265071Y-142846D01*
X263542Y-141680D01*
X262887Y-139638D01*
X263324Y-137596D01*
X264416Y-136138D01*
X265944Y-135263D01*
X267472D01*
X269001Y-135846D01*
X270311Y-137305D01*
G01X281479Y-135263D02*
X286719D01*
G01X284099D02*
Y-152763D01*
G01X281479D02*
X286719D01*
G01X297232Y-135263D02*
Y-152763D01*
X305966D01*
G01X314296D02*
Y-135263D01*
G01X322592D02*
X314296Y-146055D01*
G01X323902Y-152763D02*
X318007Y-141097D01*
G01X330049Y-158596D02*
X343149D01*
G01X354099Y-135263D02*
Y-152763D01*
G01X349077Y-135263D02*
X359121D01*
G01X253482Y-90263D02*
Y-107763D01*
X262216D01*
G01X279279D02*
Y-96097D01*
G01Y-98138D02*
X278406Y-96972D01*
X277095Y-96388D01*
X275567Y-96097D01*
X274039Y-96680D01*
X272729Y-97846D01*
X271855Y-99596D01*
X271419Y-101930D01*
X271855Y-104263D01*
X272729Y-106013D01*
X274039Y-107180D01*
X275567Y-107763D01*
X277095Y-107471D01*
X278406Y-106597D01*
X279279Y-105430D01*
G01X288264Y-113013D02*
X289574Y-113596D01*
X291321Y-113013D01*
X292412Y-111847D01*
X293286Y-110388D01*
X294595Y-105722D01*
X297434Y-96097D01*
G01X290447D02*
X294595Y-105722D01*
G01X307074Y-99888D02*
X314061D01*
X313406Y-97846D01*
X312314Y-96680D01*
X310786Y-96097D01*
X309257Y-96388D01*
X307947Y-97263D01*
X307074Y-99305D01*
X306637Y-101055D01*
Y-102805D01*
X307074Y-104555D01*
X308166Y-106305D01*
X309476Y-107471D01*
X311004Y-107763D01*
X312532Y-107180D01*
X314061Y-105430D01*
G01X324792Y-107763D02*
Y-96097D01*
G01Y-98430D02*
X325884Y-97263D01*
X326976Y-96388D01*
X328504Y-96097D01*
X329595Y-96388D01*
X330906Y-97263D01*
G01X342074Y-105722D02*
X343166Y-106888D01*
X344694Y-107763D01*
X346004D01*
X347314Y-107180D01*
X348187Y-106305D01*
X348624Y-105139D01*
X348406Y-103388D01*
X347532Y-102513D01*
X343602Y-100763D01*
X342729Y-98721D01*
X343166Y-97263D01*
X344039Y-96388D01*
X345349Y-96097D01*
X346659Y-96388D01*
X347969Y-97263D01*
G01X253150Y31496D02*
X344488D01*
G01X253150Y39370D02*
G03Y31496I0J-3937D01*
G01D02*
X344488D01*
G01X253150Y39370D02*
G03Y31496I0J-3937D01*
G01Y1937008D02*
X344496D01*
G01X253150D02*
G03Y1929134I0J-3937D01*
G01Y1937008D02*
X344496D01*
G01X253150D02*
G03Y1929134I0J-3937D01*
G01X356299Y0D02*
X417323D01*
G01X352362Y3937D02*
G03X356299Y0I3937J0D01*
G01X352362Y35433D02*
Y3937D01*
G01Y35433D02*
G03X348425Y39370I-3937J0D01*
G01X340551Y0D02*
G03X344488Y3937I0J3937D01*
G01Y7874D02*
Y3937D01*
G01X352362Y7874D02*
G03X344488I-3937J0D01*
G01Y31496D02*
G03X352362I3937J0D01*
G01X356299Y0D02*
X417323D01*
G01X352362Y3937D02*
G03X356299Y0I3937J0D01*
G01X352362Y35433D02*
Y3937D01*
G01Y35433D02*
G03X348425Y39370I-3937J0D01*
G01X340551Y0D02*
G03X344488Y3937I0J3937D01*
G01Y7874D02*
Y3937D01*
G01X352362Y7874D02*
G03X344488I-3937J0D01*
G01Y31496D02*
G03X352362I3937J0D01*
G01X348425Y1929134D02*
G03X352362Y1933071I0J3937D01*
G01Y1964567D02*
Y1933071D01*
G01X356299Y1968504D02*
G03X352362Y1964567I0J-3937D01*
G01X417323Y1968504D02*
X356299D01*
G01X344496Y1964567D02*
G03X340559Y1968504I-3937J0D01*
G01X344496Y1960889D02*
Y1964567D01*
G01Y1960889D02*
G03X352370I3937J0D01*
G01Y1937008D02*
G03X344496I-3937J0D01*
G01X348425Y1929134D02*
G03X352362Y1933071I0J3937D01*
G01Y1964567D02*
Y1933071D01*
G01X356299Y1968504D02*
G03X352362Y1964567I0J-3937D01*
G01X417323Y1968504D02*
X356299D01*
G01X344496Y1964567D02*
G03X340559Y1968504I-3937J0D01*
G01X344496Y1960889D02*
Y1964567D01*
G01Y1960889D02*
G03X352370I3937J0D01*
G01Y1937008D02*
G03X344496I-3937J0D01*
G01X404346Y-107763D02*
Y-90263D01*
X408712D01*
X410459Y-91138D01*
X411769Y-92305D01*
X412861Y-94054D01*
X413734Y-96097D01*
X413952Y-99013D01*
X413734Y-101930D01*
X412861Y-103972D01*
X411769Y-105722D01*
X410459Y-106888D01*
X408712Y-107763D01*
X404346D01*
G01X423374Y-99888D02*
X430361D01*
X429706Y-97846D01*
X428614Y-96680D01*
X427086Y-96097D01*
X425557Y-96388D01*
X424247Y-97263D01*
X423374Y-99305D01*
X422937Y-101055D01*
Y-102805D01*
X423374Y-104555D01*
X424466Y-106305D01*
X425776Y-107471D01*
X427304Y-107763D01*
X428832Y-107180D01*
X430361Y-105430D01*
G01X440874Y-105722D02*
X441966Y-106888D01*
X443494Y-107763D01*
X444804D01*
X446114Y-107180D01*
X446987Y-106305D01*
X447424Y-105139D01*
X447206Y-103388D01*
X446332Y-102513D01*
X442402Y-100763D01*
X441529Y-98721D01*
X441966Y-97263D01*
X442839Y-96388D01*
X444149Y-96097D01*
X445459Y-96388D01*
X446769Y-97263D01*
G01X461649Y-96097D02*
Y-107763D01*
G01Y-91430D02*
X461212Y-91138D01*
Y-90555D01*
X461649Y-90263D01*
X462086Y-90555D01*
Y-91138D01*
X461649Y-91430D01*
G01X476092Y-112138D02*
X477621Y-113305D01*
X479367Y-113596D01*
X480895Y-113305D01*
X482206Y-111847D01*
X483079Y-109805D01*
Y-96097D01*
G01Y-98430D02*
X482206Y-97263D01*
X480895Y-96388D01*
X479367Y-96097D01*
X477621Y-96680D01*
X476529Y-97846D01*
X475655Y-99888D01*
X475219Y-101930D01*
X475437Y-103680D01*
X476311Y-105722D01*
X477621Y-107180D01*
X479367Y-107763D01*
X480677Y-107471D01*
X482206Y-106305D01*
X483079Y-105139D01*
G01X492937Y-107763D02*
Y-96097D01*
G01Y-99013D02*
X493811Y-97555D01*
X495121Y-96388D01*
X496867Y-96097D01*
X498395Y-96388D01*
X499706Y-97555D01*
X500361Y-99596D01*
Y-107763D01*
G01X510874Y-99888D02*
X517861D01*
X517206Y-97846D01*
X516114Y-96680D01*
X514586Y-96097D01*
X513057Y-96388D01*
X511747Y-97263D01*
X510874Y-99305D01*
X510437Y-101055D01*
Y-102805D01*
X510874Y-104555D01*
X511966Y-106305D01*
X513276Y-107471D01*
X514804Y-107763D01*
X516332Y-107180D01*
X517861Y-105430D01*
G01X528592Y-107763D02*
Y-96097D01*
G01Y-98430D02*
X529684Y-97263D01*
X530776Y-96388D01*
X532304Y-96097D01*
X533395Y-96388D01*
X534706Y-97263D01*
G01X429134Y3937D02*
G03X433071Y0I3937J0D01*
G01X429134Y1964567D02*
Y3937D01*
G01X433071Y0D02*
X494095D01*
G01X421260Y3937D02*
Y1964567D01*
G01X417323Y0D02*
G03X421260Y3937I0J3937D01*
G01X429134Y11811D02*
G03X421260I-3937J0D01*
G01X429134Y3937D02*
G03X433071Y0I3937J0D01*
G01X429134Y1964567D02*
Y3937D01*
G01X433071Y0D02*
X494095D01*
G01X421260Y3937D02*
Y1964567D01*
G01X417323Y0D02*
G03X421260Y3937I0J3937D01*
G01X429134Y11811D02*
G03X421260I-3937J0D01*
G01Y42520D02*
G03X429134I3937J0D01*
G01X421260D02*
G03X429134I3937J0D01*
G01Y278740D02*
G03X421260I-3937J0D01*
G01X429134D02*
G03X421260I-3937J0D01*
G01Y309449D02*
G03X429134I3937J0D01*
G01X421260D02*
G03X429134I3937J0D01*
G01Y545669D02*
G03X421260I-3937J0D01*
G01X429134D02*
G03X421260I-3937J0D01*
G01Y576378D02*
G03X429134I3937J0D01*
G01X421260D02*
G03X429134I3937J0D01*
G01Y831496D02*
G03X421260I-3937J0D01*
G01X429134D02*
G03X421260I-3937J0D01*
G01Y862205D02*
G03X429134I3937J0D01*
G01X421260D02*
G03X429134I3937J0D01*
G01Y1106299D02*
G03X421260I-3937J0D01*
G01X429134D02*
G03X421260I-3937J0D01*
G01Y1137008D02*
G03X429134I3937J0D01*
G01X421260D02*
G03X429134I3937J0D01*
G01Y1392126D02*
G03X421260I-3937J0D01*
G01X429134D02*
G03X421260I-3937J0D01*
G01Y1422835D02*
G03X429134I3937J0D01*
G01X421260D02*
G03X429134I3937J0D01*
G01Y1659055D02*
G03X421260I-3937J0D01*
G01X429134D02*
G03X421260I-3937J0D01*
G01Y1689764D02*
G03X429134I3937J0D01*
G01X421260D02*
G03X429134I3937J0D01*
G01Y1925984D02*
G03X421260I-3937J0D01*
G01X429134D02*
G03X421260I-3937J0D01*
G01X433071Y1968504D02*
G03X429134Y1964567I0J-3937D01*
G01X494095Y1968504D02*
X433071D01*
G01X421260Y1964567D02*
G03X417323Y1968504I-3937J0D01*
G01X421260Y1956693D02*
G03X429134I3937J0D01*
G01X433071Y1968504D02*
G03X429134Y1964567I0J-3937D01*
G01X494095Y1968504D02*
X433071D01*
G01X421260Y1964567D02*
G03X417323Y1968504I-3937J0D01*
G01X421260Y1956693D02*
G03X429134I3937J0D01*
G01X433071Y1968504D02*
G03X429134Y1964567I0J-3937D01*
G01X421260D02*
G03X417323Y1968504I-3937J0D01*
G01X448096Y-152763D02*
Y-135263D01*
X452462D01*
X454209Y-136138D01*
X455519Y-137305D01*
X456611Y-139054D01*
X457484Y-141097D01*
X457702Y-144013D01*
X457484Y-146930D01*
X456611Y-148972D01*
X455519Y-150722D01*
X454209Y-151888D01*
X452462Y-152763D01*
X448096D01*
G01X470399Y-141097D02*
Y-152763D01*
G01Y-136430D02*
X469962Y-136138D01*
Y-135555D01*
X470399Y-135263D01*
X470836Y-135555D01*
Y-136138D01*
X470399Y-136430D01*
G01X487899Y-152763D02*
X486589Y-152471D01*
X485279Y-151305D01*
X484405Y-149263D01*
X483969Y-146930D01*
X484405Y-144596D01*
X485279Y-142555D01*
X486589Y-141388D01*
X487899Y-141097D01*
X489209Y-141388D01*
X490519Y-142555D01*
X491392Y-144596D01*
X491611Y-146930D01*
X491392Y-149263D01*
X490519Y-151305D01*
X489209Y-152471D01*
X487899Y-152763D01*
G01X501969Y39370D02*
G03X498032Y35433I0J-3937D01*
G01Y3937D02*
Y35433D01*
G01X494095Y0D02*
G03X498032Y3937I0J3937D01*
G01X505897Y0D02*
X648386D01*
G01X505897Y7615D02*
Y0D01*
G01X597244Y31496D02*
X505897D01*
G01Y7615D02*
G03X498023I-3937J0D01*
G01Y31496D02*
G03X505897I3937J0D01*
G01X501969Y39370D02*
G03X498032Y35433I0J-3937D01*
G01Y3937D02*
Y35433D01*
G01X494095Y0D02*
G03X498032Y3937I0J3937D01*
G01X505897Y0D02*
X620827D01*
G01X505897Y7615D02*
Y0D01*
G01X597244Y31496D02*
X505897D01*
G01Y7615D02*
G03X498023I-3937J0D01*
G01Y31496D02*
G03X505897I3937J0D01*
G01X501969Y39370D02*
X631890D01*
G01X501969D02*
X631890D01*
G01X498032Y1964567D02*
G03X494095Y1968504I-3937J0D01*
G01X498032Y1933071D02*
Y1960630D01*
G01Y1933071D02*
G03X501969Y1929134I3937J0D01*
G01X631890D02*
X501969D01*
G01X505906Y1960630D02*
Y1968504D01*
G01D02*
X648386D01*
G01X597244Y1937008D02*
X505906D01*
G01X498032Y1960630D02*
G03X505906I3937J0D01*
G01Y1937008D02*
G03X498032I-3937J0D01*
G01Y1964567D02*
G03X494095Y1968504I-3937J0D01*
G01X498032Y1933071D02*
Y1964567D01*
G01Y1933071D02*
G03X501969Y1929134I3937J0D01*
G01X631890D02*
X501969D01*
G01X505906Y1960630D02*
Y1968504D01*
G01D02*
X620827D01*
G01X597244Y1937008D02*
X505906D01*
G01X498032Y1960630D02*
G03X505906I3937J0D01*
G01Y1937008D02*
G03X498032I-3937J0D01*
G01X575349Y-152763D02*
Y-135263D01*
X572729Y-138763D01*
G01Y-152763D02*
X577969D01*
G01X588701Y-138180D02*
X590011Y-136430D01*
X591539Y-135555D01*
X593286Y-135263D01*
X595469Y-135846D01*
X596997Y-137305D01*
X597434Y-139054D01*
X597216Y-140805D01*
X596342Y-142263D01*
X591976Y-145180D01*
X590011Y-147221D01*
X588701Y-150139D01*
X588264Y-152763D01*
X597434D01*
G01X606419Y-153346D02*
X614279Y-135263D01*
G01X627849D02*
X626102Y-135846D01*
X624792Y-137305D01*
X623919Y-139054D01*
X623264Y-141388D01*
X623046Y-144013D01*
X623264Y-146638D01*
X623919Y-148972D01*
X624792Y-150722D01*
X626102Y-152180D01*
X627849Y-152763D01*
X629595Y-152180D01*
X630906Y-150722D01*
X631779Y-148972D01*
X632434Y-146638D01*
X632652Y-144013D01*
X632434Y-141388D01*
X631779Y-139054D01*
X630906Y-137305D01*
X629595Y-135846D01*
X627849Y-135263D01*
G01X644912Y-152763D02*
X645349Y-148972D01*
X646004Y-145763D01*
X646877Y-142846D01*
X647969Y-139638D01*
X649716Y-135263D01*
X640982D01*
G01X658919Y-153346D02*
X666779Y-135263D01*
G01X676201Y-138180D02*
X677511Y-136430D01*
X679039Y-135555D01*
X680786Y-135263D01*
X682969Y-135846D01*
X684497Y-137305D01*
X684934Y-139054D01*
X684716Y-140805D01*
X683842Y-142263D01*
X679476Y-145180D01*
X677511Y-147221D01*
X676201Y-150139D01*
X675764Y-152763D01*
X684934D01*
G01X697849Y-135263D02*
X696102Y-135846D01*
X694792Y-137305D01*
X693919Y-139054D01*
X693264Y-141388D01*
X693046Y-144013D01*
X693264Y-146638D01*
X693919Y-148972D01*
X694792Y-150722D01*
X696102Y-152180D01*
X697849Y-152763D01*
X699595Y-152180D01*
X700906Y-150722D01*
X701779Y-148972D01*
X702434Y-146638D01*
X702652Y-144013D01*
X702434Y-141388D01*
X701779Y-139054D01*
X700906Y-137305D01*
X699595Y-135846D01*
X697849Y-135263D01*
G01X715349Y-152763D02*
Y-135263D01*
X712729Y-138763D01*
G01Y-152763D02*
X717969D01*
G01X728701Y-138180D02*
X730011Y-136430D01*
X731539Y-135555D01*
X733286Y-135263D01*
X735469Y-135846D01*
X736997Y-137305D01*
X737434Y-139054D01*
X737216Y-140805D01*
X736342Y-142263D01*
X731976Y-145180D01*
X730011Y-147221D01*
X728701Y-150139D01*
X728264Y-152763D01*
X737434D01*
G01X623046Y-107763D02*
Y-90263D01*
X627412D01*
X629159Y-91138D01*
X630469Y-92305D01*
X631561Y-94054D01*
X632434Y-96097D01*
X632652Y-99013D01*
X632434Y-101930D01*
X631561Y-103972D01*
X630469Y-105722D01*
X629159Y-106888D01*
X627412Y-107763D01*
X623046D01*
G01X649279D02*
Y-96097D01*
G01Y-98138D02*
X648406Y-96972D01*
X647095Y-96388D01*
X645567Y-96097D01*
X644039Y-96680D01*
X642729Y-97846D01*
X641855Y-99596D01*
X641419Y-101930D01*
X641855Y-104263D01*
X642729Y-106013D01*
X644039Y-107180D01*
X645567Y-107763D01*
X647095Y-107471D01*
X648406Y-106597D01*
X649279Y-105430D01*
G01X662849Y-90263D02*
Y-107763D01*
G01X659792Y-96097D02*
X665906D01*
G01X677074Y-99888D02*
X684061D01*
X683406Y-97846D01*
X682314Y-96680D01*
X680786Y-96097D01*
X679257Y-96388D01*
X677947Y-97263D01*
X677074Y-99305D01*
X676637Y-101055D01*
Y-102805D01*
X677074Y-104555D01*
X678166Y-106305D01*
X679476Y-107471D01*
X681004Y-107763D01*
X682532Y-107180D01*
X684061Y-105430D01*
G01X635827Y31496D02*
G03X643701Y39370I0J7874D01*
G01X650689Y19685D02*
G03I-6988J0D01*
G01X635827Y31496D02*
X627953D01*
G01X597244D02*
G03Y39370I0J3937D01*
G01X627953D02*
G03Y31496I0J-3937D01*
G01X650689Y19685D02*
G03I-6988J0D01*
G01X635827Y31496D02*
X627953D01*
G01X597244D02*
G03Y39370I0J3937D01*
G01X627953D02*
G03Y31496I0J-3937D01*
G01X635827Y161417D02*
Y43307D01*
G01X631890Y39370D02*
G03X635827Y43307I0J3937D01*
G01X631890Y39370D02*
G03X635827Y43307I0J3937D01*
G01X643701Y169256D02*
G03X635827I-3937J0D01*
G01X643701D02*
G03X635827I-3937J0D01*
G01Y161417D02*
Y1807087D01*
G01Y161417D02*
Y1807087D01*
G01Y199965D02*
G03X643701I3937J0D01*
G01X635827D02*
G03X643701I3937J0D01*
G01Y436186D02*
G03X635827I-3937J0D01*
G01X643701D02*
G03X635827I-3937J0D01*
G01Y466894D02*
G03X643701I3937J0D01*
G01X635827D02*
G03X643701I3937J0D01*
G01Y703115D02*
G03X635827I-3937J0D01*
G01Y733823D02*
G03X643701I3937J0D01*
G01Y703115D02*
G03X635827I-3937J0D01*
G01Y733823D02*
G03X643701I3937J0D01*
G01X635827Y997603D02*
G03X643701I3937J0D01*
G01Y970832D02*
G03X635827I-3937J0D01*
G01Y997603D02*
G03X643701I3937J0D01*
G01Y970832D02*
G03X635827I-3937J0D01*
G01Y1265320D02*
G03X643701I3937J0D01*
G01Y1234611D02*
G03X635827I-3937J0D01*
G01Y1265320D02*
G03X643701I3937J0D01*
G01Y1234611D02*
G03X635827I-3937J0D01*
G01X643701Y1501541D02*
G03X635827I-3937J0D01*
G01X643701D02*
G03X635827I-3937J0D01*
G01Y1532249D02*
G03X643701I3937J0D01*
G01X635827D02*
G03X643701I3937J0D01*
G01Y1768470D02*
G03X635827I-3937J0D01*
G01X643701D02*
G03X635827I-3937J0D01*
G01Y1799178D02*
G03X643701I3937J0D01*
G01X635827D02*
G03X643701I3937J0D01*
G01X635827Y1818898D02*
Y1807087D01*
G01Y1818898D02*
Y1925197D01*
G01Y1818898D02*
Y1925197D01*
G01D02*
G03X631890Y1929134I-3937J0D01*
G01X635827Y1925197D02*
G03X631890Y1929134I-3937J0D01*
G01X643701D02*
G03X635827Y1937008I-7874J0D01*
G01X650689Y1948819D02*
G03I-6988J0D01*
G01X627953Y1937008D02*
X635827D01*
G01X627953D02*
G03Y1929134I0J-3937D01*
G01X597244D02*
G03Y1937008I0J3937D01*
G01X650689Y1948819D02*
G03I-6988J0D01*
G01X627953Y1937008D02*
X635827D01*
G01X627953D02*
G03Y1929134I0J-3937D01*
G01X597244D02*
G03Y1937008I0J3937D01*
G01X650689Y1948819D02*
G03I-6988J0D01*
G01X648386Y0D02*
G03X663386Y15000I0J15000D01*
G01Y1953504D02*
Y15000D01*
G01X643701Y169256D02*
Y39370D01*
G01Y436186D02*
Y199965D01*
G01Y703115D02*
Y466894D01*
G01Y970832D02*
Y733823D01*
G01Y1234611D02*
Y997603D01*
G01Y1501541D02*
Y1265320D01*
G01Y1768470D02*
Y1532249D01*
G01Y1929134D02*
Y1799178D01*
G01X663386Y1953504D02*
G03X648386Y1968504I-15000J0D01*
G01X155500Y1204433D02*
X150500D01*
Y1206517D01*
X150750Y1207183D01*
X151083Y1207600D01*
X151750Y1207767D01*
X152417Y1207600D01*
X152833Y1207100D01*
X153083Y1206517D01*
Y1204433D01*
G01Y1206517D02*
X155500Y1207767D01*
G01Y1211700D02*
X155417Y1211033D01*
X155083Y1210450D01*
X154583Y1209950D01*
X154000Y1209617D01*
X153333Y1209450D01*
X152667D01*
X152000Y1209617D01*
X151417Y1209950D01*
X150917Y1210450D01*
X150583Y1211033D01*
X150500Y1211700D01*
X150583Y1212367D01*
X150917Y1212950D01*
X151417Y1213450D01*
X152000Y1213783D01*
X152667Y1213950D01*
X153333D01*
X154000Y1213783D01*
X154583Y1213450D01*
X155083Y1212950D01*
X155417Y1212367D01*
X155500Y1211700D01*
G01Y1215550D02*
X150500D01*
G01Y1219050D02*
X155500D01*
G01X153000D02*
Y1215550D01*
G01X154833Y1221150D02*
X155250Y1221817D01*
X155500Y1222567D01*
Y1223233D01*
X155250Y1223900D01*
X154833Y1224400D01*
X154250Y1224650D01*
X153667Y1224483D01*
X153167Y1224067D01*
X152833Y1223317D01*
X152667Y1222317D01*
X152333Y1221733D01*
X151750Y1221483D01*
X151167Y1221650D01*
X150750Y1222067D01*
X150500Y1222650D01*
Y1223233D01*
X150667Y1223817D01*
X151083Y1224317D01*
G01X150917Y1235933D02*
X150667Y1235433D01*
X150500Y1234850D01*
Y1234183D01*
X150750Y1233433D01*
X151167Y1232850D01*
X151667Y1232433D01*
X152500Y1232100D01*
X153250Y1232017D01*
X154000Y1232183D01*
X154500Y1232433D01*
X155000Y1232933D01*
X155333Y1233517D01*
X155500Y1234100D01*
Y1234683D01*
X155333Y1235267D01*
X155083Y1235767D01*
X154750Y1236183D01*
G01X155500Y1239700D02*
X155417Y1239200D01*
X155083Y1238700D01*
X154500Y1238367D01*
X153833Y1238200D01*
X153167Y1238367D01*
X152583Y1238700D01*
X152250Y1239200D01*
X152167Y1239700D01*
X152250Y1240200D01*
X152583Y1240700D01*
X153167Y1241033D01*
X153833Y1241117D01*
X154500Y1241033D01*
X155083Y1240700D01*
X155417Y1240200D01*
X155500Y1239700D01*
G01Y1242800D02*
X152167D01*
G01X153083D02*
X152667Y1243050D01*
X152333Y1243467D01*
X152167Y1244050D01*
X152333Y1244633D01*
X152667Y1245050D01*
X153083Y1245300D01*
X155500D01*
G01X153083D02*
X152667Y1245550D01*
X152333Y1245967D01*
X152167Y1246550D01*
X152333Y1247133D01*
X152667Y1247550D01*
X153167Y1247800D01*
X155500D01*
G01X157167Y1249400D02*
X152167D01*
G01X152917D02*
X152500Y1249817D01*
X152250Y1250233D01*
X152167Y1250900D01*
X152250Y1251483D01*
X152667Y1252067D01*
X153250Y1252317D01*
X153833Y1252400D01*
X154417Y1252317D01*
X155000Y1252067D01*
X155333Y1251567D01*
X155500Y1250900D01*
X155417Y1250317D01*
X155167Y1249733D01*
X154833Y1249400D01*
G01X155500Y1256500D02*
X150500D01*
G01X152167Y1262100D02*
X155500D01*
G01X150833D02*
X150750Y1261933D01*
X150583D01*
X150500Y1262100D01*
X150583Y1262267D01*
X150750D01*
X150833Y1262100D01*
G01X155500Y1269200D02*
X152167D01*
G01X152750D02*
X152417Y1268867D01*
X152250Y1268367D01*
X152167Y1267783D01*
X152333Y1267200D01*
X152667Y1266700D01*
X153167Y1266367D01*
X153833Y1266200D01*
X154500Y1266367D01*
X155000Y1266700D01*
X155333Y1267200D01*
X155500Y1267783D01*
X155417Y1268367D01*
X155167Y1268867D01*
X154833Y1269200D01*
G01X155500Y1271883D02*
X152167D01*
G01X153000D02*
X152583Y1272217D01*
X152250Y1272717D01*
X152167Y1273383D01*
X152250Y1273967D01*
X152583Y1274467D01*
X153167Y1274717D01*
X155500D01*
G01X152583Y1280233D02*
X152250Y1279650D01*
X152167Y1279150D01*
X152333Y1278483D01*
X152667Y1277983D01*
X153250Y1277650D01*
X153833Y1277567D01*
X154417Y1277650D01*
X154917Y1277983D01*
X155333Y1278483D01*
X155500Y1279150D01*
X155333Y1279733D01*
X155000Y1280233D01*
G01X153250Y1283250D02*
Y1285917D01*
X152667Y1285667D01*
X152333Y1285250D01*
X152167Y1284667D01*
X152250Y1284083D01*
X152500Y1283583D01*
X153083Y1283250D01*
X153583Y1283083D01*
X154083D01*
X154583Y1283250D01*
X155083Y1283667D01*
X155417Y1284167D01*
X155500Y1284750D01*
X155333Y1285333D01*
X154833Y1285917D01*
G01X183500Y1356250D02*
X183458Y1355917D01*
X183292Y1355625D01*
X183042Y1355375D01*
X182750Y1355208D01*
X182417Y1355125D01*
X182083D01*
X181750Y1355208D01*
X181458Y1355375D01*
X181208Y1355625D01*
X181042Y1355917D01*
X181000Y1356250D01*
X181042Y1356583D01*
X181208Y1356875D01*
X181458Y1357125D01*
X181750Y1357292D01*
X182083Y1357375D01*
X182417D01*
X182750Y1357292D01*
X183042Y1357125D01*
X183292Y1356875D01*
X183458Y1356583D01*
X183500Y1356250D01*
G01X181000Y1359350D02*
X183500D01*
G01X181000Y1358392D02*
Y1360308D01*
G01X183500Y1361617D02*
X181000D01*
Y1362617D01*
X181125Y1362950D01*
X181417Y1363200D01*
X181750Y1363283D01*
X182083Y1363200D01*
X182333Y1362992D01*
X182458Y1362617D01*
Y1361617D01*
G01X183000Y1367817D02*
X183250Y1368025D01*
X183417Y1368275D01*
X183500Y1368567D01*
X183417Y1368900D01*
X183250Y1369150D01*
X183000Y1369400D01*
X182667Y1369483D01*
X181000D01*
G01Y1370833D02*
X182792D01*
X183167Y1371000D01*
X183417Y1371333D01*
X183500Y1371750D01*
X183417Y1372167D01*
X183167Y1372500D01*
X182792Y1372667D01*
X181000D01*
G01X183500Y1373767D02*
X181000D01*
X183083Y1374850D01*
X181000Y1375933D01*
X183500D01*
G01Y1377117D02*
X181000D01*
Y1378117D01*
X181125Y1378450D01*
X181417Y1378700D01*
X181750Y1378783D01*
X182083Y1378700D01*
X182333Y1378492D01*
X182458Y1378117D01*
Y1377117D01*
G01X183500Y1381883D02*
Y1380217D01*
X181000D01*
Y1381883D01*
G01X182208Y1381217D02*
Y1380217D01*
G01X183500Y1383317D02*
X181000D01*
Y1384358D01*
X181125Y1384692D01*
X181292Y1384900D01*
X181625Y1384983D01*
X181958Y1384900D01*
X182167Y1384650D01*
X182292Y1384358D01*
Y1383317D01*
G01Y1384358D02*
X183500Y1384983D01*
G01X183167Y1389475D02*
X183375Y1389808D01*
X183500Y1390183D01*
Y1390517D01*
X183375Y1390850D01*
X183167Y1391100D01*
X182875Y1391225D01*
X182583Y1391142D01*
X182333Y1390933D01*
X182167Y1390558D01*
X182083Y1390058D01*
X181917Y1389767D01*
X181625Y1389642D01*
X181333Y1389725D01*
X181125Y1389933D01*
X181000Y1390225D01*
Y1390517D01*
X181083Y1390808D01*
X181292Y1391058D01*
G01X183500Y1394283D02*
Y1392617D01*
X181000D01*
Y1394283D01*
G01X182208Y1393617D02*
Y1392617D01*
G01X181000Y1396550D02*
X183500D01*
G01X181000Y1395592D02*
Y1397508D01*
G01Y1399650D02*
X183500D01*
G01X181000Y1398692D02*
Y1400608D01*
G01Y1402250D02*
Y1403250D01*
G01Y1402750D02*
X183500D01*
G01Y1402250D02*
Y1403250D01*
G01Y1404892D02*
X181000D01*
X183500Y1406808D01*
X181000D01*
G01X182250Y1409200D02*
Y1410033D01*
X183000D01*
X183250Y1409783D01*
X183417Y1409492D01*
X183500Y1409075D01*
X183417Y1408658D01*
X183250Y1408367D01*
X183000Y1408117D01*
X182708Y1407950D01*
X182375Y1407867D01*
X182083D01*
X181833Y1407950D01*
X181542Y1408117D01*
X181292Y1408367D01*
X181125Y1408617D01*
X181000Y1408950D01*
Y1409242D01*
X181083Y1409575D01*
X181250Y1409825D01*
G01X176500Y1367417D02*
X174000D01*
Y1368417D01*
X174125Y1368750D01*
X174417Y1369000D01*
X174750Y1369083D01*
X175083Y1369000D01*
X175333Y1368792D01*
X175458Y1368417D01*
Y1367417D01*
G01X176500Y1371350D02*
X174000D01*
X174500Y1370850D01*
G01X176500D02*
Y1371850D01*
G01Y1377917D02*
X174000D01*
Y1378917D01*
X174125Y1379250D01*
X174417Y1379500D01*
X174750Y1379583D01*
X175083Y1379500D01*
X175333Y1379292D01*
X175458Y1378917D01*
Y1377917D01*
G01X174417Y1381058D02*
X174167Y1381308D01*
X174042Y1381600D01*
X174000Y1381933D01*
X174083Y1382350D01*
X174292Y1382642D01*
X174542Y1382725D01*
X174792Y1382683D01*
X175000Y1382517D01*
X175417Y1381683D01*
X175708Y1381308D01*
X176125Y1381058D01*
X176500Y1380975D01*
Y1382725D01*
G01Y1387917D02*
X174000D01*
Y1388917D01*
X174125Y1389250D01*
X174417Y1389500D01*
X174750Y1389583D01*
X175083Y1389500D01*
X175333Y1389292D01*
X175458Y1388917D01*
Y1387917D01*
G01X176000Y1390933D02*
X176292Y1391183D01*
X176458Y1391517D01*
X176500Y1391892D01*
X176458Y1392225D01*
X176250Y1392558D01*
X176000Y1392767D01*
X175750Y1392808D01*
X175458Y1392725D01*
X175250Y1392433D01*
X175167Y1392142D01*
Y1391767D01*
G01Y1392142D02*
X175042Y1392392D01*
X174833Y1392600D01*
X174583Y1392683D01*
X174333Y1392600D01*
X174125Y1392392D01*
X174000Y1392017D01*
X174042Y1391642D01*
X174208Y1391267D01*
G01X199417Y1358458D02*
X199167Y1358708D01*
X199042Y1359000D01*
X199000Y1359333D01*
X199083Y1359750D01*
X199292Y1360042D01*
X199542Y1360125D01*
X199792Y1360083D01*
X200000Y1359917D01*
X200417Y1359083D01*
X200708Y1358708D01*
X201125Y1358458D01*
X201500Y1358375D01*
Y1360125D01*
G01X200667Y1361808D02*
Y1362892D01*
G01X201000Y1364533D02*
X201292Y1364783D01*
X201458Y1365117D01*
X201500Y1365492D01*
X201458Y1365825D01*
X201250Y1366158D01*
X201000Y1366367D01*
X200750Y1366408D01*
X200458Y1366325D01*
X200250Y1366033D01*
X200167Y1365742D01*
Y1365367D01*
G01Y1365742D02*
X200042Y1365992D01*
X199833Y1366200D01*
X199583Y1366283D01*
X199333Y1366200D01*
X199125Y1365992D01*
X199000Y1365617D01*
X199042Y1365242D01*
X199208Y1364867D01*
G01X201583Y1368550D02*
X201542Y1368467D01*
X201458D01*
X201417Y1368550D01*
X201458Y1368633D01*
X201542D01*
X201583Y1368550D01*
G01X200458D02*
X200417Y1368467D01*
X200333D01*
X200292Y1368550D01*
X200333Y1368633D01*
X200417D01*
X200458Y1368550D01*
G01X201500Y1373708D02*
X199000Y1374750D01*
X201500Y1375792D01*
G01X200625Y1375417D02*
Y1374083D01*
G01X199000Y1376933D02*
X200792D01*
X201167Y1377100D01*
X201417Y1377433D01*
X201500Y1377850D01*
X201417Y1378267D01*
X201167Y1378600D01*
X200792Y1378767D01*
X199000D01*
G01Y1380950D02*
X201500D01*
G01X199000Y1379992D02*
Y1381908D01*
G01X201500Y1384050D02*
X201458Y1383717D01*
X201292Y1383425D01*
X201042Y1383175D01*
X200750Y1383008D01*
X200417Y1382925D01*
X200083D01*
X199750Y1383008D01*
X199458Y1383175D01*
X199208Y1383425D01*
X199042Y1383717D01*
X199000Y1384050D01*
X199042Y1384383D01*
X199208Y1384675D01*
X199458Y1384925D01*
X199750Y1385092D01*
X200083Y1385175D01*
X200417D01*
X200750Y1385092D01*
X201042Y1384925D01*
X201292Y1384675D01*
X201458Y1384383D01*
X201500Y1384050D01*
G01Y1389417D02*
X199000D01*
Y1390458D01*
X199125Y1390792D01*
X199292Y1391000D01*
X199625Y1391083D01*
X199958Y1391000D01*
X200167Y1390750D01*
X200292Y1390458D01*
Y1389417D01*
G01Y1390458D02*
X201500Y1391083D01*
G01Y1394183D02*
Y1392517D01*
X199000D01*
Y1394183D01*
G01X200208Y1393517D02*
Y1392517D01*
G01X200667Y1395908D02*
Y1396992D01*
G01X199000Y1399550D02*
X201500D01*
G01X199000Y1398592D02*
Y1400508D01*
G01X201500Y1401817D02*
X199000D01*
Y1402858D01*
X199125Y1403192D01*
X199292Y1403400D01*
X199625Y1403483D01*
X199958Y1403400D01*
X200167Y1403150D01*
X200292Y1402858D01*
Y1401817D01*
G01Y1402858D02*
X201500Y1403483D01*
G01Y1405750D02*
X200375D01*
X199000Y1404917D01*
G01Y1406583D02*
X200375Y1405750D01*
G01X192000Y1359250D02*
X189500D01*
X190000Y1358750D01*
G01X192000D02*
Y1359750D01*
G01X191167Y1361808D02*
Y1362892D01*
G01X189917Y1364658D02*
X189667Y1364908D01*
X189542Y1365200D01*
X189500Y1365533D01*
X189583Y1365950D01*
X189792Y1366242D01*
X190042Y1366325D01*
X190292Y1366283D01*
X190500Y1366117D01*
X190917Y1365283D01*
X191208Y1364908D01*
X191625Y1364658D01*
X192000Y1364575D01*
Y1366325D01*
G01X192083Y1368550D02*
X192042Y1368467D01*
X191958D01*
X191917Y1368550D01*
X191958Y1368633D01*
X192042D01*
X192083Y1368550D01*
G01X190958D02*
X190917Y1368467D01*
X190833D01*
X190792Y1368550D01*
X190833Y1368633D01*
X190917D01*
X190958Y1368550D01*
G01X189500Y1373917D02*
X192000D01*
Y1375583D01*
G01Y1376808D02*
X189500Y1377850D01*
X192000Y1378892D01*
G01X191125Y1378517D02*
Y1377183D01*
G01X189500Y1380950D02*
X192000D01*
G01X189500Y1379992D02*
Y1381908D01*
G01X189708Y1384967D02*
X189583Y1384717D01*
X189500Y1384425D01*
Y1384092D01*
X189625Y1383717D01*
X189833Y1383425D01*
X190083Y1383217D01*
X190500Y1383050D01*
X190875Y1383008D01*
X191250Y1383092D01*
X191500Y1383217D01*
X191750Y1383467D01*
X191917Y1383758D01*
X192000Y1384050D01*
Y1384342D01*
X191917Y1384633D01*
X191792Y1384883D01*
X191625Y1385092D01*
G01X192000Y1386275D02*
X189500D01*
G01Y1388025D02*
X192000D01*
G01X190750D02*
Y1386275D01*
G01X192000Y1355417D02*
X189500D01*
Y1356417D01*
X189625Y1356750D01*
X189917Y1357000D01*
X190250Y1357083D01*
X190583Y1357000D01*
X190833Y1356792D01*
X190958Y1356417D01*
Y1355417D01*
G01X201500D02*
X199000D01*
Y1356417D01*
X199125Y1356750D01*
X199417Y1357000D01*
X199750Y1357083D01*
X200083Y1357000D01*
X200333Y1356792D01*
X200458Y1356417D01*
Y1355417D01*
M02*
